# GT_VPDB_BOM_20230323.xlsx — BOM Sharing Template (bom)
| Part Description | Manufacturer | Manufacturing Part Number | Quantity | Location (CRD) | ROOM |
| IC EEPROM(8P) M24256-BRMN6TP(SO8) | SGS-THOMSON(STMicroelectronics) | M24256-BRMN6TP | 1 | U10 |  |
| IC CTRL(48P)ADM1272-1ACPZ-RL(LFCSP_WQ) | ANALOG DEVICES | ADM1272-1ACPZ-RL | 1 | PU7 | HSC1_BOM2 |
| IC(22P)MP5022CGQV-Z(QFN) | Monolithic Power Systems, Inc (MPS International Ltd.) | MP5022CGQV-Z | 1 | U32 |  |
| IC CTRL(14P)MPQ8626GD-Z(QFN) | Monolithic Power Systems, Inc (MPS International Ltd.) | MPQ8626GD-Z | 1 | PU5 |  |
| IC (20P) PCA9545APW (TSSOP) | PHILIPS LTD,. | PCA9545APW | 1 | U25 |  |
| IC(24P) PCA9555PW(TSSOP)EP | PHILIPS LTD,. | PCA9555PW | 1 | U4 |  |
| IC(5P) 74LVC1G125GV (SOT753) | PHILIPS LTD,. | 74LVC1G125GV | 2 | U8,U9 |  |
| IC OTHER(5P) 74LVC1G08W5-7(SOT25) | DIODES TAIWAN CO.,LTD. | 74LVC1G08W5-7 | 1 | U19 |  |
| IC OTHER(5P) 74LVC1G126SE-7 (SOT353) | DIODES TAIWAN CO.,LTD. | 74LVC1G126SE-7 | 1 | U5 |  |
| CONV D-D(40-60V,11.8V,110A)Q50SN120A1NKD | DELTA ELECTRONIC IND. CO., LTD. DELTA ELECTRONICS COMPONENT(WUJIANG)LTD | Q50SN120A1NKDSF | 3 | PU2,PU3,PU6 |  |
| TRANS SMD MMBT3904-7-F(40V,200MA,8W) | DIODES TAIWAN CO.,LTD. | MMBT3904-7-F | 1 | PQ15 |  |
| TRANS MOSFET DMN53D0L-7(50V,0.5A,0.5W) | DIODES TAIWAN CO.,LTD. | DMN53D0L-7 | 1 | U23 | HSC1_BOM2 |
| TRANS MOSFET DMN53D0L-7(50V,0.5A,0.5W) | DIODES TAIWAN CO.,LTD. | DMN53D0L-7 | 2 | U24,U27 |  |
| TRANS MOSFET DMN53D0L-7(50V,0.5A,0.5W) | DIODES TAIWAN CO.,LTD. | DMN53D0L-7 | 4 | U36,U37,U39,U40 |  |
| TR MOSFET 2N7002K(60V,300MA,0.35W)SOT-23 | PAN JIT INTERNATIONAL INC. | 2N7002K | 1 | U20 |  |
| TRANS MOS PSMN3R7-100BSE(100V,120A,405W) | Nexperia B.V. | PSMN3R7-100BSE | 6 | PQ1,PQ2,PQ3,PQ4,PQ5,PQ6 |  |
| DIODE SMD SDMK0340L-7-F(40V,30MA) | DIODES TAIWAN CO.,LTD. | SDMK0340L-7-F | 1 | D6 |  |
| DIODE SMD B340A-13-F(40V,3A)SCHOTTKY | DIODES TAIWAN CO.,LTD. | B340A-13-F | 1 | D5 |  |
| DIODE SMD B340A-13-F(40V,3A)SCHOTTKY | DIODES TAIWAN CO.,LTD. | B340A-13-F | 2 | D11,D12 |  |
| DIODE SMD B380-13-F(80V,100A,SCHOTTKY) | DIODES TAIWAN CO.,LTD. | B380-13-F | 1 | PD8 |  |
| DIODE SMD 5.0SMDJ60A(60V,51.70A) | LITTELFUSE INC. | 5.0SMDJ60A | 2 | PD6,PD7 |  |
| DIODE TVS SMBJ14A(14V,25.9A,600W) | LITTELFUSE INC. | SMBJ14A | 1 | D4 |  |
| LED SMD(2P) BLUE(LTST-C281TBKT-5A) | LITEON ELECTRONIC CO., LTD. | LTST-C281TBKT-5A | 3 | D1,D2,D3 |  |
| CAP ELEC DIP 100U 100V(20%,10*20)NPN | NIPPON CHEMI-CON | EKY-101ETD101MJ201 | 6 | PC15,PC16,PC43,PC44,PC113,PC114 |  |
| CAP OSCON DIP 2200U 16V(20%,10*20)NPN | NIPPON CHEMI-CON | APSG160ETD222MJ20S | 9 | PC40,PC41,PC42,PC68,PC69,PC70,PC134,PC135,PC136 |  |
| CAP CHIP 100P 50V(+-5%.NPO.0402) | RTECH TECHNOLOGY CO.,LTD.(Compostar) | CC0402N101J3SST-S | 1 | PC111 |  |
| CAP CHIP 560P 50V(+-10%,X7R,0402) | MURATA ERIE N.A. INC TAIWAN BRANCH Okayama Murata Mfg.Co.,Ltd.Wakura Murata Mfg. Co., Ltd. (Peregrine Semiconductor Corp) | GRM155R71H561K | 1 | C98 |  |
| CAP CHIP 1000P 50V(+-5%.X7R.0402) | ACER PERIPHERALS INC.(Darfon Electronics Corp.) Darfon Precisions(Suzhou)Co.,LTD | C1005X7R102JGT | 3 | PC29,PC57,PC123 |  |
| CAP CHIP 3300P 50V(+-10%.X7R.0402) | RTECH TECHNOLOGY CO.,LTD.(Compostar) | CC0402X332K3OST | 1 | PC110 |  |
| CAP CHIP 8200P 25V (+-10%.X7R.0402) | RTECH TECHNOLOGY CO.,LTD.(Compostar) | CC0402X822K2OST-S | 1 | PC12 | HSC1_BOM2 |
| CAP CHIP 0.01U 50V(+-10%,X7R,0402) | MURATA ERIE N.A. INC TAIWAN BRANCH Okayama Murata Mfg.Co.,Ltd.Wakura Murata Mfg. Co., Ltd. (Peregrine Semiconductor Corp) | WBM155R71H103K | 1 | PC561 | HSC1_BOM2 |
| CAP CHIP 0.01U 100V(+-10%.X7R.0603) | MURATA ERIE N.A. INC TAIWAN BRANCH Okayama Murata Mfg.Co.,Ltd.Wakura Murata Mfg. Co., Ltd. (Peregrine Semiconductor Corp) | GRM188R72A103K | 2 | C69,C89 |  |
| CAP CHIP 0.047U 25V(+-10% X7R 0402) | MURATA ERIE N.A. INC TAIWAN BRANCH Okayama Murata Mfg.Co.,Ltd.Wakura Murata Mfg. Co., Ltd. (Peregrine Semiconductor Corp) | GRM155R71E473K | 1 | C96 |  |
| CAP CHIP 0.047UF 100V(+-10%,X7R,0805) | MURATA ERIE N.A. INC TAIWAN BRANCH Okayama Murata Mfg.Co.,Ltd.Wakura Murata Mfg. Co., Ltd. (Peregrine Semiconductor Corp) | GRM21BR72A473K | 1 | PC13 | HSC1_BOM2 |
| CAP CHIP 0.1U 16V(10%.X7R.0402) | MURATA ERIE N.A. INC TAIWAN BRANCH Okayama Murata Mfg.Co.,Ltd.Wakura Murata Mfg. Co., Ltd. (Peregrine Semiconductor Corp) | WBM155R71C104K | 7 | C4,C5,C48,C51,C56,C70,C90 |  |
| CAP CHIP 0.1U 16V(10%.X7R.0402) | MURATA ERIE N.A. INC TAIWAN BRANCH Okayama Murata Mfg.Co.,Ltd.Wakura Murata Mfg. Co., Ltd. (Peregrine Semiconductor Corp) | WBM155R71C104K | 3 | C8,C9,C10 |  |
| CAP CHIP 0.1U 25V(+-10%,X7R,0402) | YAGEO CORPORATION | CC0402KRX7R8BB104 | 1 | C93 |  |
| CAP CHIP 0.1U 25V(+-10%,X7R,0402) | YAGEO CORPORATION | CC0402KRX7R8BB104 | 2 | PC1,PC2 |  |
| CAP CHIP 0.1U 25V(+-10%,X7R,0402) | YAGEO CORPORATION | CC0402KRX7R8BB104 | 2 | PC9,PC557 | HSC1_BOM2 |
| CAP CHIP 0.1U 25V(+-10%,X7R,0402) | YAGEO CORPORATION | CC0402KRX7R8BB104 | 3 | PC28,PC56,PC122 |  |
| CAP CHIP 100NF 50V(+-10%,X7R,0402) | YAGEO CORPORATION | CC0402KRX7R9BB104 | 1 | C97 |  |
| CAP CHIP 100NF 50V(+-10%,X7R,0402) | YAGEO CORPORATION | CC0402KRX7R9BB104 | 2 | PC99,PC102 |  |
| CAP CHIP 100NF 50V(+-10%,X7R,0402) | YAGEO CORPORATION | CC0402KRX7R9BB104 | 1 | PC104 |  |
| CAP CHIP 0.1U 100V(+-10%.X7R.1206)H1.25 | WALSIN TECHNOLOGY CORPORATION | 1206B104K101CT | 1 | PC558 | HSC1_BOM2 |
| CAP CHIP 0.22U 25V(10%,X7R,0402) | TAIYO YUDEN CO.,LTD | TMK105B7224KV-FR | 1 | C94 |  |
| CAP CHIP 0.22U 25V(10%,X7R,0402) | TAIYO YUDEN CO.,LTD | TMK105B7224KV-FR | 1 | PC11 | HSC1_BOM2 |
| CAP CHIP 0.22U 25V(10%,X7R,0402) | TAIYO YUDEN CO.,LTD | TMK105B7224KV-FR | 2 | PC103,PC112 |  |
| CAP CHIP 1U 25V(+-10%.X7R.0603)MUR | MURATA ERIE N.A. INC TAIWAN BRANCH Okayama Murata Mfg.Co.,Ltd.Wakura Murata Mfg. Co., Ltd. (Peregrine Semiconductor Corp) | GRM188R71E105K | 1 | PC562 | HSC1_BOM2 |
| CAP CHIP 1UF 25V(+-10%,X6S,0402) | MURATA ERIE N.A. INC TAIWAN BRANCH Okayama Murata Mfg.Co.,Ltd.Wakura Murata Mfg. Co., Ltd. (Peregrine Semiconductor Corp) | GRM155C81E105K | 1 | C91 |  |
| CAP CHIP 1UF 25V(+-10%,X6S,0402) | MURATA ERIE N.A. INC TAIWAN BRANCH Okayama Murata Mfg.Co.,Ltd.Wakura Murata Mfg. Co., Ltd. (Peregrine Semiconductor Corp) | GRM155C81E105K | 3 | C100,C102,PC109 |  |
| CAP CHIP 1UF 25V(+-10%,X6S,0402) | MURATA ERIE N.A. INC TAIWAN BRANCH Okayama Murata Mfg.Co.,Ltd.Wakura Murata Mfg. Co., Ltd. (Peregrine Semiconductor Corp) | GRM155C81E105K | 1 | PC10 | HSC1_BOM2 |
| CAP CHIP 1U 100V(10%.1206.X7R)MUR | MURATA ERIE N.A. INC TAIWAN BRANCH Okayama Murata Mfg.Co.,Ltd.Wakura Murata Mfg. Co., Ltd. (Peregrine Semiconductor Corp) | GRF31CR72A105K | 1 | PC559 | HSC1_BOM2 |
| CAP CHIP 2.2UF 16V(20%,X7R,0603) | TAIYO YUDEN CO.,LTD | EMK107BB7225MA-T | 1 | C95 |  |
| CAP CHIP 2.2UF 100V(+-10%,X7R,1206) | MURATA ERIE N.A. INC TAIWAN BRANCH Okayama Murata Mfg.Co.,Ltd.Wakura Murata Mfg. Co., Ltd. (Peregrine Semiconductor Corp) | GRM31CR72A225K | 42 | PC18,PC19,PC20,PC21,PC22,C22,PC23,C23,C24,C25,C26,C27,C28,C29,C30,C31,C32,C33,C34,C35,C36,C37,C38,C39,C40,C41,C42,C43,C44,C45,PC46,PC47,PC48,PC49,PC50,PC51,PC116,PC117,PC118,PC119,PC120,PC121 |  |
| CAP CHIP 10U 25V(+-10%,X6S,0805)MUR | MURATA ERIE N.A. INC TAIWAN BRANCH Okayama Murata Mfg.Co.,Ltd.Wakura Murata Mfg. Co., Ltd. (Peregrine Semiconductor Corp) | GRM21BC81E106K | 1 | C92 |  |
| CAP CHIP 22U 6.3V(+-20%,X6S,0805)MUR | MURATA ERIE N.A. INC TAIWAN BRANCH Okayama Murata Mfg.Co.,Ltd.Wakura Murata Mfg. Co., Ltd. (Peregrine Semiconductor Corp) | GRM21BC80J226M | 4 | PC105,PC106,PC107,PC108 |  |
| CAP CHIP 22UF 16V(+-20%,X6S,0805)MUR | MURATA ERIE N.A. INC TAIWAN BRANCH Okayama Murata Mfg.Co.,Ltd.Wakura Murata Mfg. Co., Ltd. (Peregrine Semiconductor Corp) | GRM21BC81C226M | 11 | PC86,PC87,PC88,PC89,PC90,PC91,PC92,PC93,PC94,PC95,C101 |  |
| CAP CHIP 22UF 16V(+-20%,X6S,0805)MUR | MURATA ERIE N.A. INC TAIWAN BRANCH Okayama Murata Mfg.Co.,Ltd.Wakura Murata Mfg. Co., Ltd. (Peregrine Semiconductor Corp) | GRM21BC81C226M | 23 | PC30,PC31,PC32,PC33,PC34,PC35,PC36,PC37,PC38,PC39,PC64,PC65,PC66,PC67,PC100,PC101,PC127,PC128,PC132,PC133,PC566,PC567,PC568 |  |
| RES CHIP 0 1/16W +-5%(0402)EF | WALSIN TECHNOLOGY CORPORATION | WR04X000PTR | 3 | PR50,PR65,PR318 | BRICK1_BOM1 |
| RES CHIP 0 1/16W +-5%(0402)EF | WALSIN TECHNOLOGY CORPORATION | WR04X000PTR | 26 | R6,R7,R32,PR52,PR67,R65,R67,R76,R77,R78,R79,PR92,R160,R165,R166,R170,R172,R173,R195,R197,R198,R199,R202,PR319,R5904,PR6973 |  |
| RES CHIP 0 1/16W +-5%(0402)EF | WALSIN TECHNOLOGY CORPORATION | WR04X000PTR | 2 | PR6967,PR6968 | HSC1_BOM2 |
| RES CHIP 0 1/16W +-5%(0402)EF | WALSIN TECHNOLOGY CORPORATION | WR04X000PTR | 4 | R27,R113,R185,R189 |  |
| RES CHIP 0 1/16W +-5%(0402)EF | WALSIN TECHNOLOGY CORPORATION | WR04X000PTR | 9 | R81,R144,R145,R151,R158,R159,R169,R5860,R5861 | HSC1_BOM2 |
| RES CHIP 0 1/8W +-5% (0805)EF | WALSIN TECHNOLOGY CORPORATION | WR08X000PTR | 1 | R5890 |  |
| RES CHIP 10 1/10W +-1%(0603)EF | WALSIN TECHNOLOGY CORPORATION | WR06X10R0FTR | 6 | PR8,PR12,PR13,PR14,PR15,PR16 |  |
| RES CHIP 10 1/10W +-1%(0603)EF | WALSIN TECHNOLOGY CORPORATION | WR06X10R0FTR | 4 | PR6958,PR6959,PR6960,PR6961 | HSC1_BOM2 |
| RES CHIP 33 1/16W +-1%(0402)EF | WALSIN TECHNOLOGY CORPORATION | WR04X33R0FTR | 13 | R4,R5,R41,R42,R70,R117,R118,R139,R164,R171,R184,R196,PR313 |  |
| RES CHIP 33 1/16W +-1%(0402)EF | WALSIN TECHNOLOGY CORPORATION | WR04X33R0FTR | 2 | R5878,R5879 |  |
| RES CHIP 49.9 1/10W +-1%(0603)EF | YAGEO CORPORATION | RC0603FR-0749R9P | 1 | R5895 |  |
| RES CHIP 75 1/16W +-1%(0402)EF | WALSIN TECHNOLOGY CORPORATION | WR04X75R0FTR | 1 | R59 |  |
| RES CHIP 100 1/16W +-1%(0402)EF | WALSIN TECHNOLOGY CORPORATION | WR04X1000FTR | 2 | R71,R96 |  |
| RES CHIP 100 1/2W+-5%(1206)SR | RALEC ELECTRONIC CO. | RTG06101JTP | 1 | PR5 | HSC1_BOM2 |
| RES CHIP 150 1/16W +-1%(0402)EF | WALSIN TECHNOLOGY CORPORATION | WR04X1500FTR | 1 | R141 |  |
| RES CHIP 200 1/16W +-1%(0402)EF | WALSIN TECHNOLOGY CORPORATION | WR04X2000FTR | 1 | R35 |  |
| RES CHIP 220 1/16W +-5%(0402)EF | WALSIN TECHNOLOGY CORPORATION | WR04X221 JTR | 2 | R43,R45 |  |
| RES CHIP 301 1/16W +-1%(0402)EF | WALSIN TECHNOLOGY CORPORATION | WR04X3010FTR | 1 | R69 |  |
| RES CHIP 316 1/16W +-1%(0402)EF | WALSIN TECHNOLOGY CORPORATION | WR04X3160FTR | 3 | R56,R58,R61 |  |
| RES CHIP 1K 1/16W +-1%(0402)EF | WALSIN TECHNOLOGY CORPORATION | WR04X1001FTR | 2 | PR20,R90 | HSC1_BOM2 |
| RES CHIP 1K 1/16W +-1%(0402)EF | WALSIN TECHNOLOGY CORPORATION | WR04X1001FTR | 8 | R19,R21,R23,R97,R102,R162,R175,R193 |  |
| RES CHIP 1K 1/16W +-1%(0402)EF | WALSIN TECHNOLOGY CORPORATION | WR04X1001FTR | 1 | R94 | BRICK_DELTA |
| RES CHIP 1K 1/16W +-1%(0402)EF | WALSIN TECHNOLOGY CORPORATION | WR04X1001FTR | 6 | R95,R133,R135,R137,R5892,R5917 |  |
| RES CHIP 1K 1/4W +-5%(1206)EF | RALEC ELECTRONIC CO. | FTT06102JTP | 5 | R55,R57,R60,R62,R63 |  |
| RES CHIP 1.65K 1/16W +-1%(0402)EF | WALSIN TECHNOLOGY CORPORATION | WR04X1651FTR | 1 | PR9 |  |
| RES CHIP 2.2 1/16W +-1%(0402)EF | WALSIN TECHNOLOGY CORPORATION | WR04W2R20FTR | 1 | PR314 |  |
| RES CHIP 2.21K 1/16W +-1%(0402)EF | WALSIN TECHNOLOGY CORPORATION | WR04X2211FTR | 1 | PR10 |  |
| RES CHIP 2.26K 1/16W +-1%(0402)EF | WALSIN TECHNOLOGY CORPORATION | WR04X2261FTR | 1 | PR6931 | HSC1_BOM2 |
| RES CHIP 2.43K 1/16W +-1%(0402)EF | WALSIN TECHNOLOGY CORPORATION | WR04X2431FTR | 1 | PR6932 | HSC1_BOM2 |
| RES CHIP 3.3K 1/8W +-1%(0805)EF | EVER OHMS TECHNOLOGY CO., LTD. | CRG0805F3K30P05Z | 3 | PR59,PR74,PR321 |  |
| RES CHIP 4.7K 1/16W +-5%(0402)EF | WALSIN TECHNOLOGY CORPORATION | WR04X472 JTR | 7 | R17,R39,R100,R101,R105,R106,R142 |  |
| RES CHIP 4.7K 1/16W +-5%(0402)EF | WALSIN TECHNOLOGY CORPORATION | WR04X472 JTR | 2 | R24,R5903 |  |
| RES CHIP 4.7K 1/16W +-5%(0402)EF | WALSIN TECHNOLOGY CORPORATION | WR04X472 JTR | 1 | R150 | HSC1_BOM2 |
| RES CHIP 8.45K 1/16W +-1%( 0402)EF | WALSIN TECHNOLOGY CORPORATION | WR04X8451FTR | 1 | R5888 |  |
| RES CHIP 10K 1/16W +-1%(0402)EF | WALSIN TECHNOLOGY CORPORATION | WR04X1002FTR | 1 | PR93 | HSC1_BOM2 |
| RES CHIP 10K 1/16W +-1%(0402)EF | WALSIN TECHNOLOGY CORPORATION | WR04X1002FTR | 1 | R83 |  |
| RES CHIP 10K 1/16W +-1%(0402)EF | WALSIN TECHNOLOGY CORPORATION | WR04X1002FTR | 13 | R1,R2,R125,R126,R127,R128,R129,R130,R131,R132,R5891,R5897,R5899 |  |
| RES CHIP 10K 1/16W +-5%(0402)EF | WALSIN TECHNOLOGY CORPORATION | WR04X103 JTR | 5 | R34,R37,PR87,R203,R5909 |  |
| RES CHIP 10.5K 1/16W +-1%(0402)EF | RALEC ELECTRONIC CO. | FTT021052FTH | 1 | PR89 |  |
| RES CHIP 11.5K 1/16W +-1%(0402)EF | WALSIN TECHNOLOGY CORPORATION | WR04X1152FTR | 1 | R149 | HSC1_BOM2 |
| RES CHIP 11.5K 1/16W +-1%(0402)EF | WALSIN TECHNOLOGY CORPORATION | WR04X1152FTR | 6 | R5885,R5887,R5911,R5916,R5931,R5933 |  |
| RES CHIP 12.4K 1/16W +-1%(0402)EF | YAGEO CORPORATION | RC0402FR-0712K4P | 1 | PR91 |  |
| RES CHIP 16.9K 1/16W +-1%(0402)EF | YAGEO CORPORATION | RC0402FR-0716K9P | 1 | PR31 | HSC1_BOM2 |
| RES CHIP 20K 1/16W +-1%(0402)EF | WALSIN TECHNOLOGY CORPORATION | WR04X2002FTR | 1 | R5902 |  |
| RES CHIP 20K 1/8W +-1%(0805)EF | WALSIN TECHNOLOGY CORPORATION | WR08X2002FTR | 1 | PR32 | HSC1_BOM2 |
| RES CHIP 37.4K 1/16W +-1%(0402)EF | WALSIN TECHNOLOGY CORPORATION | WR04X3742FTR | 1 | R5901 |  |
| RES CHIP 43.2K 1/16W +-1%(0402)EF | WALSIN TECHNOLOGY CORPORATION | WR04X4322FTR | 1 | PR6933 | HSC1_BOM2 |
| RES CHIP 46.4K 1/16W +-1%(0402)EF | WALSIN TECHNOLOGY CORPORATION | WR04X4642FTR | 1 | R5900 |  |
| RES CHIP 48.7K 1/16W +-1%(0402)EF | YAGEO CORPORATION | RC0402FR-0748K7P | 1 | PR21 | HSC1_BOM2 |
| RES CHIP 48.7K 1/16W +-1%(0402)EF | YAGEO CORPORATION | RC0402FR-0748K7P | 1 | R5919 |  |
| RES CHIP 53.6K 1/16W +-1%(0402)EF | WALSIN TECHNOLOGY CORPORATION | WR04X5362FTR | 1 | R82 |  |
| RES CHIP 56K 1/16W +-1%(0402)EF | WALSIN TECHNOLOGY CORPORATION | WR04X5602FTR | 1 | PR90 |  |
| RES CHIP 60.4K 1/16W +-1%(0402)EF | WALSIN TECHNOLOGY CORPORATION | WR04X6042FTR | 1 | PR88 |  |
| RES CHIP 69.8K 1/16W +-1%(0402)EF | WALSIN TECHNOLOGY CORPORATION | WR04X6982FTR | 1 | PR320 |  |
| RES CHIP 88.7K 1/16W +-1%(0402) | YAGEO CORPORATION | RC0402FR-0788K7L | 1 | PR73 |  |
| RES CHIP 95.3K 1/8W +-1%(0805)EF | WALSIN TECHNOLOGY CORPORATION | WR08X9532FTR | 2 | PR2,PR3 |  |
| RES CHIP 95.3K 1/8W +-1%(0805)EF | WALSIN TECHNOLOGY CORPORATION | WR08X9532FTR | 2 | PR4,PR17 | HSC1_BOM2 |
| RES CHIP 95.3K 1/8W +-1%(0805)EF | WALSIN TECHNOLOGY CORPORATION | WR08X9532FTR | 1 | R5889 |  |
| RES CHIP 100K 1/16W +-1%(0402)EF | WALSIN TECHNOLOGY CORPORATION | WR04X1003FTR | 2 | PR35,PR6934 | HSC1_BOM2 |
| RES CHIP 100K 1/16W +-5%(0402)EF | WALSIN TECHNOLOGY CORPORATION | WR04X104 JTR | 4 | R33,R140,R187,R188 |  |
| RES CHIP 107K 1/16W +-1%(0402)EF | YAGEO CORPORATION | RC0402FR-07107KP | 1 | PR58 |  |
| RES CHIP 120K 1/16W +-1%(0402)EF | YAGEO CORPORATION | RC0402FR-07120KP | 1 | R5894 |  |
| RES CHIP 174K 1/8W +-1%(0805)EF | EVER OHMS TECHNOLOGY CO., LTD. | CRG0805F174KP05Z | 1 | R148 | HSC1_BOM2 |
| RES CHIP 174K 1/8W +-1%(0805)EF | EVER OHMS TECHNOLOGY CO., LTD. | CRG0805F174KP05Z | 6 | R5884,R5886,R5910,R5915,R5930,R5932 |  |
| RES CHIP 390K 1/16W +-1%(0402)EF | WALSIN TECHNOLOGY CORPORATION | WR04X3903FTR | 1 | PR37 | HSC1_BOM2 |
| RES CHIP 2.05M 1/8W +-1%(0805)EF | EVER OHMS TECHNOLOGY CO., LTD. | CRG0805F2M05P05Z | 1 | PR19 | HSC1_BOM2 |
| RES CHIP 2.05M 1/8W +-1%(0805)EF | EVER OHMS TECHNOLOGY CO., LTD. | CRG0805F2M05P05Z | 1 | R5918 |  |
| IND SMD 1.5UH 20% 53A(MSE-12HZN1R5M-M1Q) | MAG. LAYERS (MAG.LAYERS Scientific-Technics Co., Ltd) | MSE-12HZN1R5M-M1Q | 3 | L1,L3,L5 |  |
| IND SMD 4.7U20%5.5A(PCMC063T-4R7MN) | CYNTEC CO., LTD. | PCMC063T-4R7MN | 1 | PL2 |  |
| EMI FILTER BLM18SN220TN1D(22,8000MA) | MURATA ERIE N.A. INC TAIWAN BRANCH Okayama Murata Mfg.Co.,Ltd.Wakura Murata Mfg. Co., Ltd. (Peregrine Semiconductor Corp) | BLM18SN220TN1D | 1 | PL1 |  |
| CONN DIP HEADER 3P 1R MS(P2.54,H8.38) | (FOXCONN) HON HAI PRECISION INDUSTRY KANG ZHUN PRESION TOOLING(KUN SHAN)CO.,LTD FuYu Precision Component(KunShan)Co.,Ltd.FuRui Precision Components(KunShan)Co.,LtiKang Zhun Precision Tooling(KunShan)Co.,Ltd, FuHon Precision Components(KunShan)Co., | HBB1037-L300D-8H | 2 | JP2,JP3 |  |
| CONN DIP HEADER 32P 2R MR(P1.27,H7.5) | AMPHENOL EAST ASIA LIMITED (Amphenol-TCS) (Shanghai Amphenol Airwave Communication Electronics Co.,L......(Skip) | 10164834-002QLF | 1 | J7 |  |
| CONN DIP HEADER 36P 4R MS(P2.54,H12.7) | AMPHENOL EAST ASIA LIMITED (Amphenol-TCS) (Shanghai Amphenol Airwave Communication Electronics Co.,L......(Skip) | 10106267-4001501LF | 1 | J5 |  |
| CONN DIP HEADER 48P 4R MS(P2.54,H12.7) | AMPHENOL EAST ASIA LIMITED (Amphenol-TCS) (Shanghai Amphenol Airwave Communication Electronics Co.,L......(Skip) | 10106267-6000402LF | 1 | J2 |  |
| CONN DIP HEADER 60P 4R MS(P2.54,H12.7) | AMPHENOL EAST ASIA LIMITED (Amphenol-TCS) (Shanghai Amphenol Airwave Communication Electronics Co.,L......(Skip) | 10106267-6003502LF | 1 | J1 |  |
| CONN DIP HOUSING 1P FR(H9.95) | AMPHENOL EAST ASIA LIMITED (Amphenol-TCS) (Shanghai Amphenol Airwave Communication Electronics Co.,L......(Skip) | 10045597-101LF | 2 | J14,J15 |  |
| FUSE SMD 20A/125V(FAST,UL/CSA) | LITTELFUSE INC. | 0456020.ER | 1 | FS1 |  |
| RES CHIP 0.0005 2W +-1%(2512) | TA-I TECHNOLOGY CO.,LTD. | RLM25FEEMR0005 | 1 | R5873 |  |
| RES CHIP 0.0003 4W +-1%(2725) | RALEC ELECTRONIC CO. | LR2725-24R0003F1 | 2 | PR1,PR315 |  |
| THUMB SCW 6_32_63 GN F0D(FBF0D010,3A)FVT | Fivetech Technology Inc. | FBIX500301 | 2 | H19,H20 |  |
| VR HS 9F EX F0T(FBF0T001,3A)ART | AURAS TECHNOLOGY COMPANY (AURAS TECHNOLOGY (KUNSHAN) CO., LTD)  Pel horng(GuangZhou) Technology Co.,......(Skip) | FBF0T00101 | 4 | PU2_HS,PU3_HS,PU4_HS,PU6_HS |  |
| PLBL LBL HIGHTEMP17X12 S2L(HCS2L067,R3C) | HWAKUAN LABEL & PRINTING CO.,LTD | HCS2L06701 | 1 | STAGE_LABEL |  |
| LABEL SERIAL PL S6I(HCS6I019,3A) | HWAKUAN LABEL & PRINTING CO.,LTD | HCS6I01901 | 1 | PN_LABEL |  |
| MB LABEL  (HCT70001,REV3A) | HWAKUAN LABEL & PRINTING CO.,LTD | HCT70001 | 1 | REWORK_LABEL |  |
| SCREW M2.5*5.5-I(BZN,NYLOK,D5.5,T1.0)STL | SCREW TECH INDUDTRY CO., LTD. | MM25055I000 | 2 | J14_SCREW,J15_SCREW |  |
| SCREW M3.0*5.0-C(BNI,D6.0,T1.5)STEEL | SCREW TECH INDUDTRY CO., LTD. | MM30050C030 | 12 | PU2_SCREW0,PU2_SCREW1,PU2_SCREW2,PU3_SCREW0,PU3_SCREW1,PU3_SCREW2,PU4_SCREW0,PU4_SCREW1,PU4_SCREW2,PU6_SCREW0,PU6_SCREW1,PU6_SCREW2 |  |
| SCREW M3*12-H(NI,NYLOK,D5.5,T2.6)STEEL | SCREW TECH INDUDTRY CO., LTD. | MS30120H000 | 6 | J1_SCREW0,J1_SCREW1,J2_SCREW0,J2_SCREW1,J5_SCREW0,J5_SCREW1 |  |
| NUT SMD M3 H3.53 T6U(MBT6U008,3A)STL | SCREW TECH INDUDTRY CO., LTD. | MBT6U00801 | 2 | H24,H25 |  |
| INS MYLAR PDB TOP F0T(FCF0T014,R3A) | CHING WEI INDUSTRY CO.,LTD (JING JIA INDUSTRIAL GLOBAL CO.,LTD) | FCF0T01401 | 1 | mylar |  |
| HEX NUT M3-2MM STEEL KQ2 | SCREW TECH INDUDTRY CO., LTD. | MBAG500201 | 4 | J1_NUT0,J1_NUT1,J2_NUT0,J2_NUT1 |  |
| WASHER FAN IXAE(MCIXA001,R3A)PLASTIC PIK | PIN GOOD ENTERPRISE CO.,LTDSUZHOU PINGOOD ENTERPRISE CO.,LTD | MCIXA00101 | 4 | J1_PLASTIC0,J1_PLASTIC1,J2_PLASTIC0,J2_PLASTIC1 |  |
